# S9S_MB_2U (Grand Teton) — schematic netlist excerpt (pin names and nets, part order shuffled) for the footprints in the layout excerpt that follows; sources: Cadence DE-HDL packaged netlist, KiCad conversion of 03242023_DA0F0TMBIJ0_F0T_Motherboard_J_brd_V01_OCP.brd

R5487  Q_RES  0 5% CHIP  pkg 0402LF  page 156 : A = HP_LVC3_OCP_V3_1_EN ; B = P3V3_OCP_EN_1_R
PR1301  Q_RES  60.4K 1% CHIP  pkg 0402LF  page 282 : A = PVNN_MAIN_CPU0_MODE ; B = GND

(kicad_pcb
	(version 20260206)
	(generator "pcbnew")
	(generator_version "10.0")
	(general
		(thickness 1.6)
		(legacy_teardrops no)
	)
	(paper "A4")
	(title_block
		(title "03242023_DA0F0TMBIJ0_F0T_Motherboard_J_brd_V01_OCP.brd")
		(comment 1 "Grand Teton / footprints 3105-3106 of 6105")
	)
	(layers
		(0 "F.Cu" signal "TOP")
		(4 "In1.Cu" signal "GND")
		(6 "In2.Cu" signal "IN1")
		(8 "In3.Cu" signal "GND1")
		(10 "In4.Cu" signal "IN2")
		(12 "In5.Cu" signal "GND2")
		(14 "In6.Cu" signal "IN3")
		(16 "In7.Cu" signal "GND3")
		(18 "In8.Cu" signal "VCC")
		(20 "In9.Cu" signal "VCC1")
		(22 "In10.Cu" signal "GND4")
		(24 "In11.Cu" signal "IN4")
		(26 "In12.Cu" signal "GND5")
		(28 "In13.Cu" signal "IN5")
		(30 "In14.Cu" signal "GND6")
		(32 "In15.Cu" signal "IN6")
		(34 "In16.Cu" signal "GND7")
		(2 "B.Cu" signal "BOTTOM")
		(9 "F.Adhes" user "F.Adhesive")
		(11 "B.Adhes" user "B.Adhesive")
		(13 "F.Paste" user "Package Geometry/Pastemask Top")
		(15 "B.Paste" user "Package Geometry/Pastemask Bottom")
		(5 "F.SilkS" user "Ref Des/Silkscreen Top")
		(7 "B.SilkS" user "Ref Des/Silkscreen Bottom")
		(1 "F.Mask" user "Board Geometry/Soldermask Top")
		(3 "B.Mask" user "Board Geometry/Soldermask Bottom")
		(17 "Dwgs.User" user "User.Drawings")
		(19 "Cmts.User" user "User.Comments")
		(21 "Eco1.User" user "User.Eco1")
		(23 "Eco2.User" user "User.Eco2")
		(25 "Edge.Cuts" user "Board Geometry/Outline")
		(27 "Margin" user)
		(31 "F.CrtYd" user "Package Geometry/Place Bound Top")
		(29 "B.CrtYd" user "Package Geometry/Place Bound Bottom")
		(35 "F.Fab" user "Ref Des/Assembly Top")
		(33 "B.Fab" user "Ref Des/Assembly Bottom")
	)
	(footprint ""
		(layer "F.Cu")
		(at 434.113178 -183.84139 90)
		(property "Reference" "PR1301"
			(at 0 0 90)
			(layer "F.SilkS")
			(hide yes)
			(effects
				(font
					(size 1.27 1.27)
				)
			)
		)
		(property "Value" ""
			(at 0 0 90)
			(layer "F.Fab")
			(effects
				(font
					(size 1.27 1.27)
				)
			)
		)
		(duplicate_pad_numbers_are_jumpers no)
		(fp_line
			(start 0.7874 -0.4064)
			(end 0.7874 0.4064)
			(stroke
				(width 0.1524)
				(type default)
			)
			(layer "F.SilkS")
		)
		(fp_line
			(start -0.7874 -0.4064)
			(end 0.7874 -0.4064)
			(stroke
				(width 0.1524)
				(type default)
			)
			(layer "F.SilkS")
		)
		(fp_line
			(start 0.7874 0.4064)
			(end -0.7874 0.4064)
			(stroke
				(width 0.1524)
				(type default)
			)
			(layer "F.SilkS")
		)
		(fp_line
			(start -0.7874 0.4064)
			(end -0.7874 -0.4064)
			(stroke
				(width 0.1524)
				(type default)
			)
			(layer "F.SilkS")
		)
		(fp_line
			(start -0.12065 -0.305054)
			(end -0.12065 -0.2794)
			(stroke
				(width 0.1)
				(type default)
			)
			(layer "F.Fab")
		)
		(fp_line
			(start -0.67945 -0.305054)
			(end -0.12065 -0.305054)
			(stroke
				(width 0.1)
				(type default)
			)
			(layer "F.Fab")
		)
		(fp_line
			(start 0.67945 -0.3048)
			(end 0.67945 0.3048)
			(stroke
				(width 0.1)
				(type default)
			)
			(layer "F.Fab")
		)
		(fp_line
			(start 0.12065 -0.3048)
			(end 0.67945 -0.3048)
			(stroke
				(width 0.1)
				(type default)
			)
			(layer "F.Fab")
		)
		(fp_line
			(start 0.12065 -0.2794)
			(end 0.12065 -0.3048)
			(stroke
				(width 0.1)
				(type default)
			)
			(layer "F.Fab")
		)
		(fp_line
			(start -0.12065 -0.2794)
			(end 0.12065 -0.2794)
			(stroke
				(width 0.1)
				(type default)
			)
			(layer "F.Fab")
		)
		(fp_line
			(start 0.120396 0.2794)
			(end -0.12065 0.2794)
			(stroke
				(width 0.1)
				(type default)
			)
			(layer "F.Fab")
		)
		(fp_line
			(start -0.12065 0.2794)
			(end -0.12065 0.3048)
			(stroke
				(width 0.1)
				(type default)
			)
			(layer "F.Fab")
		)
		(fp_line
			(start 0.67945 0.3048)
			(end 0.120396 0.3048)
			(stroke
				(width 0.1)
				(type default)
			)
			(layer "F.Fab")
		)
		(fp_line
			(start 0.120396 0.3048)
			(end 0.120396 0.2794)
			(stroke
				(width 0.1)
				(type default)
			)
			(layer "F.Fab")
		)
		(fp_line
			(start -0.12065 0.3048)
			(end -0.67945 0.3048)
			(stroke
				(width 0.1)
				(type default)
			)
			(layer "F.Fab")
		)
		(fp_line
			(start -0.67945 0.3048)
			(end -0.67945 -0.305054)
			(stroke
				(width 0.1)
				(type default)
			)
			(layer "F.Fab")
		)
		(pad "1" smd circle
			(at -0.40005 0 90)
			(size 0 0)
			(layers "F.Cu" "F.Mask" "F.Paste")
			(net "PVNN_MAIN_CPU0_MODE")
		)
		(pad "2" smd circle
			(at 0.40005 0 90)
			(size 0 0)
			(layers "F.Cu" "F.Mask" "F.Paste")
			(net "GND")
		)
	)
	(footprint ""
		(layer "F.Cu")
		(at 457.52131 -42.05351)
		(property "Reference" "R5487"
			(at 0 0 0)
			(layer "F.SilkS")
			(hide yes)
			(effects
				(font
					(size 1.27 1.27)
				)
			)
		)
		(property "Value" ""
			(at 0 0 0)
			(layer "F.Fab")
			(effects
				(font
					(size 1.27 1.27)
				)
			)
		)
		(duplicate_pad_numbers_are_jumpers no)
		(fp_line
			(start -0.7874 -0.4064)
			(end 0.7874 -0.4064)
			(stroke
				(width 0.1524)
				(type default)
			)
			(layer "F.SilkS")
		)
		(fp_line
			(start -0.7874 0.4064)
			(end -0.7874 -0.4064)
			(stroke
				(width 0.1524)
				(type default)
			)
			(layer "F.SilkS")
		)
		(fp_line
			(start 0.7874 -0.4064)
			(end 0.7874 0.4064)
			(stroke
				(width 0.1524)
				(type default)
			)
			(layer "F.SilkS")
		)
		(fp_line
			(start 0.7874 0.4064)
			(end -0.7874 0.4064)
			(stroke
				(width 0.1524)
				(type default)
			)
			(layer "F.SilkS")
		)
		(fp_line
			(start -0.67945 -0.305054)
			(end -0.12065 -0.305054)
			(stroke
				(width 0.1)
				(type default)
			)
			(layer "F.Fab")
		)
		(fp_line
			(start -0.67945 0.3048)
			(end -0.67945 -0.305054)
			(stroke
				(width 0.1)
				(type default)
			)
			(layer "F.Fab")
		)
		(fp_line
			(start -0.12065 -0.305054)
			(end -0.12065 -0.2794)
			(stroke
				(width 0.1)
				(type default)
			)
			(layer "F.Fab")
		)
		(fp_line
			(start -0.12065 -0.2794)
			(end 0.12065 -0.2794)
			(stroke
				(width 0.1)
				(type default)
			)
			(layer "F.Fab")
		)
		(fp_line
			(start -0.12065 0.2794)
			(end -0.12065 0.3048)
			(stroke
				(width 0.1)
				(type default)
			)
			(layer "F.Fab")
		)
		(fp_line
			(start -0.12065 0.3048)
			(end -0.67945 0.3048)
			(stroke
				(width 0.1)
				(type default)
			)
			(layer "F.Fab")
		)
		(fp_line
			(start 0.120396 0.2794)
			(end -0.12065 0.2794)
			(stroke
				(width 0.1)
				(type default)
			)
			(layer "F.Fab")
		)
		(fp_line
			(start 0.120396 0.3048)
			(end 0.120396 0.2794)
			(stroke
				(width 0.1)
				(type default)
			)
			(layer "F.Fab")
		)
		(fp_line
			(start 0.12065 -0.3048)
			(end 0.67945 -0.3048)
			(stroke
				(width 0.1)
				(type default)
			)
			(layer "F.Fab")
		)
		(fp_line
			(start 0.12065 -0.2794)
			(end 0.12065 -0.3048)
			(stroke
				(width 0.1)
				(type default)
			)
			(layer "F.Fab")
		)
		(fp_line
			(start 0.67945 -0.3048)
			(end 0.67945 0.3048)
			(stroke
				(width 0.1)
				(type default)
			)
			(layer "F.Fab")
		)
		(fp_line
			(start 0.67945 0.3048)
			(end 0.120396 0.3048)
			(stroke
				(width 0.1)
				(type default)
			)
			(layer "F.Fab")
		)
		(pad "1" smd circle
			(at -0.40005 0)
			(size 0 0)
			(layers "F.Cu" "F.Mask" "F.Paste")
			(net "HP_LVC3_OCP_V3_1_EN")
		)
		(pad "2" smd circle
			(at 0.40005 0)
			(size 0 0)
			(layers "F.Cu" "F.Mask" "F.Paste")
			(net "P3V3_OCP_EN_1_R")
		)
	)
)
